# BASEBOARD_FAB2 (Tioga Pass) — schematic netlist excerpt (pin names and nets, part order shuffled) for the footprints in the layout excerpt that follows; sources: Cadence DE-HDL packaged netlist, KiCad conversion of Wiwynn_Tioga_Pass_MB.brd

U8G1  SN74LVC2G07DCKR-GP  pkg DISCRET-G4  page 156
  \1a\  = RST_PCH_SYSRST_BTN_OUT_N
  GND  = GND
  \2a\  = FM_PCH_PWRBTN_OUT_N
  \2y\  = FM_PCH_PWRBTN_R_N
  VCC  = P3V3_STBY
  \1y\  = RST_BMC_SYSRST_BTN_OUT_B_R_N

SH3P1  SHUNT  EMPTY  pkg SH0201  page 212 : A = VSENSE_PVCCIO_CPU0_SKT_VSEN ; B = VSENSE_PVCCIO_CPU0_AVSP
C32W1  CAP_A  0.1UF 16V 10% X7R  pkg 0402V  page 185 : A = P1V8_M2 ; B = GND

(kicad_pcb
	(version 20260206)
	(generator "pcbnew")
	(generator_version "10.0")
	(general
		(thickness 1.6)
		(legacy_teardrops no)
	)
	(paper "A4")
	(title_block
		(title "Wiwynn_Tioga_Pass_MB.brd")
		(comment 1 "Tioga Pass / footprints 4586-4588 of 4770")
	)
	(layers
		(0 "F.Cu" signal "TOP")
		(4 "In1.Cu" signal "L2GND")
		(6 "In2.Cu" signal "L3")
		(8 "In3.Cu" signal "L4GND")
		(10 "In4.Cu" signal "L5")
		(12 "In5.Cu" signal "L6GND")
		(14 "In6.Cu" signal "L7VCC")
		(16 "In7.Cu" signal "L8VCC")
		(18 "In8.Cu" signal "L9GND")
		(20 "In9.Cu" signal "L10")
		(22 "In10.Cu" signal "L11GND")
		(24 "In11.Cu" signal "L12")
		(26 "In12.Cu" signal "L13GND")
		(2 "B.Cu" signal "BOTTOM")
		(9 "F.Adhes" user "F.Adhesive")
		(11 "B.Adhes" user "B.Adhesive")
		(13 "F.Paste" user "Package Geometry/Pastemask Top")
		(15 "B.Paste" user "Package Geometry/Pastemask Bottom")
		(5 "F.SilkS" user "Ref Des/Silkscreen Top")
		(7 "B.SilkS" user "Ref Des/Silkscreen Bottom")
		(1 "F.Mask" user "Board Geometry/Soldermask Top")
		(3 "B.Mask" user "Board Geometry/Soldermask Bottom")
		(17 "Dwgs.User" user "User.Drawings")
		(19 "Cmts.User" user "User.Comments")
		(21 "Eco1.User" user "User.Eco1")
		(23 "Eco2.User" user "User.Eco2")
		(25 "Edge.Cuts" user "Board Geometry/Outline")
		(27 "Margin" user)
		(31 "F.CrtYd" user "Package Geometry/Place Bound Top")
		(29 "B.CrtYd" user "Package Geometry/Place Bound Bottom")
		(35 "F.Fab" user "Ref Des/Assembly Top")
		(33 "B.Fab" user "Ref Des/Assembly Bottom")
	)
	(footprint ""
		(layer "B.Cu")
		(at 394.95984 -37.9984 180)
		(property "Reference" "U8G1"
			(at 0 0 0)
			(layer "B.SilkS")
			(hide yes)
			(effects
				(font
					(size 1.27 1.27)
				)
				(justify mirror)
			)
		)
		(property "Value" "*"
			(at 2.3622 -8.3185 180)
			(unlocked yes)
			(layer "B.Fab")
			(hide yes)
			(effects
				(font
					(size 1.27 1.016)
					(thickness 0.1524)
				)
				(justify mirror)
			)
		)
		(property "Device Type" "SN74LVC2G07DCKR-GP_DISCRET-G4-A"
			(at 2.3622 -10.2235 180)
			(unlocked yes)
			(layer "B.Fab")
			(hide yes)
			(effects
				(font
					(size 1.27 1.016)
					(thickness 0.1524)
				)
				(justify mirror)
			)
		)
		(duplicate_pad_numbers_are_jumpers no)
		(fp_line
			(start 1.5494 1.7907)
			(end 1.5494 0.8255)
			(stroke
				(width 0.3302)
				(type default)
			)
			(layer "B.SilkS")
		)
		(fp_line
			(start 1.4478 1.7018)
			(end -1.4478 1.7018)
			(stroke
				(width 0.1524)
				(type default)
			)
			(layer "B.SilkS")
		)
		(fp_line
			(start 1.4478 -1.7018)
			(end 1.4478 1.7018)
			(stroke
				(width 0.1524)
				(type default)
			)
			(layer "B.SilkS")
		)
		(fp_line
			(start 0.5715 1.7907)
			(end 1.5494 1.7907)
			(stroke
				(width 0.3302)
				(type default)
			)
			(layer "B.SilkS")
		)
		(fp_line
			(start -1.4478 1.7018)
			(end -1.4478 -1.7018)
			(stroke
				(width 0.1524)
				(type default)
			)
			(layer "B.SilkS")
		)
		(fp_line
			(start -1.4478 -1.7018)
			(end 1.4478 -1.7018)
			(stroke
				(width 0.1524)
				(type default)
			)
			(layer "B.SilkS")
		)
		(fp_poly
			(pts
				(xy 0.6604 1.7272) (xy 1.016 2.0828) (xy 0.3048 2.0828)
			)
			(stroke
				(width 0)
				(type default)
			)
			(fill yes)
			(layer "B.SilkS")
		)
		(fp_poly
			(pts
				(xy 1.524 -1.778) (xy -1.524 -1.778) (xy -1.524 1.778) (xy 1.524 1.778)
			)
			(stroke
				(width 0)
				(type default)
			)
			(fill no)
			(layer "B.CrtYd")
		)
		(fp_poly
			(pts
				(xy 1.524 -1.778) (xy -1.524 -1.778) (xy -1.524 1.778) (xy 1.524 1.778)
			)
			(stroke
				(width 0)
				(type default)
			)
			(fill no)
			(layer "B.Fab")
		)
		(pad "1" smd rect
			(at 0.65024 0.9398)
			(size 0.4064 1.016)
			(layers "B.Cu" "B.Mask" "B.Paste")
			(net "RST_PCH_SYSRST_BTN_OUT_N")
		)
		(pad "2" smd rect
			(at 0 0.9398)
			(size 0.4064 1.016)
			(layers "B.Cu" "B.Mask" "B.Paste")
			(net "GND")
		)
		(pad "3" smd rect
			(at -0.65024 0.9398)
			(size 0.4064 1.016)
			(layers "B.Cu" "B.Mask" "B.Paste")
			(net "FM_PCH_PWRBTN_OUT_N")
		)
		(pad "4" smd rect
			(at -0.65024 -0.9398)
			(size 0.4064 1.016)
			(layers "B.Cu" "B.Mask" "B.Paste")
			(net "FM_PCH_PWRBTN_R_N")
		)
		(pad "5" smd rect
			(at 0 -0.9398)
			(size 0.4064 1.016)
			(layers "B.Cu" "B.Mask" "B.Paste")
			(net "P3V3_STBY")
		)
		(pad "6" smd rect
			(at 0.65024 -0.9398)
			(size 0.4064 1.016)
			(layers "B.Cu" "B.Mask" "B.Paste")
			(net "RST_BMC_SYSRST_BTN_OUT_B_R_N")
		)
	)
	(footprint ""
		(layer "B.Cu")
		(at 395.548358 -12.589002)
		(property "Reference" "C32W1"
			(at 0.8382 -0.67818 0)
			(unlocked yes)
			(layer "B.SilkS")
			(effects
				(font
					(size 0.4064 0.254)
					(thickness 0.1524)
				)
				(justify left mirror)
			)
		)
		(property "Value" ""
			(at 0 0 0)
			(layer "B.Fab")
			(effects
				(font
					(size 1.27 1.27)
				)
				(justify mirror)
			)
		)
		(duplicate_pad_numbers_are_jumpers no)
		(fp_poly
			(pts
				(xy -0.3048 -0.1016) (xy -0.3048 0.9906) (xy 0.3048 0.9906) (xy 0.3048 -0.1016)
			)
			(stroke
				(width 0)
				(type default)
			)
			(fill no)
			(layer "B.CrtYd")
		)
		(fp_line
			(start -0.3048 -0.1016)
			(end 0.3048 -0.1016)
			(stroke
				(width 0.1)
				(type default)
			)
			(layer "B.Fab")
		)
		(fp_line
			(start -0.3048 0.9906)
			(end -0.3048 -0.1016)
			(stroke
				(width 0.1)
				(type default)
			)
			(layer "B.Fab")
		)
		(fp_line
			(start 0.3048 -0.1016)
			(end 0.3048 0.9906)
			(stroke
				(width 0.1)
				(type default)
			)
			(layer "B.Fab")
		)
		(fp_line
			(start 0.3048 0.9906)
			(end -0.3048 0.9906)
			(stroke
				(width 0.1)
				(type default)
			)
			(layer "B.Fab")
		)
		(pad "1" smd rect
			(at 0 0 180)
			(size 0.508 0.508)
			(layers "B.Cu" "B.Mask" "B.Paste")
			(net "P1V8_M2")
		)
		(pad "2" smd rect
			(at 0 0.889 180)
			(size 0.508 0.508)
			(layers "B.Cu" "B.Mask" "B.Paste")
			(net "GND")
		)
		(zone
			(layer "B.Cu")
			(hatch none 0.5)
			(connect_pads
				(clearance 0)
			)
			(min_thickness 0.25)
			(keepout
				(tracks allowed)
				(vias not_allowed)
				(pads allowed)
				(copperpour not_allowed)
				(footprints allowed)
			)
			(placement
				(enabled no)
				(sheetname "")
			)
			(fill
				(thermal_gap 0.5)
				(thermal_bridge_width 0.5)
				(island_removal_mode 0)
			)
			(polygon
				(pts
					(xy 395.802358 -12.335002) (xy 395.294358 -12.335002) (xy 395.294358 -11.954002) (xy 395.802358 -11.954002)
				)
			)
		)
		(zone
			(layer "B.Cu")
			(hatch none 0.5)
			(connect_pads
				(clearance 0)
			)
			(min_thickness 0.25)
			(keepout
				(tracks not_allowed)
				(vias allowed)
				(pads allowed)
				(copperpour not_allowed)
				(footprints allowed)
			)
			(placement
				(enabled no)
				(sheetname "")
			)
			(fill
				(thermal_gap 0.5)
				(thermal_bridge_width 0.5)
				(island_removal_mode 0)
			)
			(polygon
				(pts
					(xy 395.802358 -11.954002) (xy 395.294358 -11.954002) (xy 395.294358 -12.335002) (xy 395.802358 -12.335002)
				)
			)
		)
	)
	(footprint ""
		(layer "B.Cu")
		(at 355.349048 -86.93404 180)
		(property "Reference" "SH3P1"
			(at 0 0 0)
			(layer "B.SilkS")
			(hide yes)
			(effects
				(font
					(size 1.27 1.27)
				)
				(justify mirror)
			)
		)
		(property "Value" ""
			(at 0 0 0)
			(layer "B.Fab")
			(effects
				(font
					(size 1.27 1.27)
				)
				(justify mirror)
			)
		)
		(duplicate_pad_numbers_are_jumpers no)
		(fp_poly
			(pts
				(xy 0.1651 -0.0508) (xy 0.1651 0.5842) (xy -0.1651 0.5842) (xy -0.1651 -0.0508)
			)
			(stroke
				(width 0)
				(type default)
			)
			(fill no)
			(layer "B.CrtYd")
		)
		(fp_line
			(start 0.1651 0.5842)
			(end 0.1651 -0.0508)
			(stroke
				(width 0.1)
				(type default)
			)
			(layer "B.Fab")
		)
		(fp_line
			(start 0.1651 -0.0508)
			(end -0.1651 -0.0508)
			(stroke
				(width 0.1)
				(type default)
			)
			(layer "B.Fab")
		)
		(fp_line
			(start -0.1651 0.5842)
			(end 0.1651 0.5842)
			(stroke
				(width 0.1)
				(type default)
			)
			(layer "B.Fab")
		)
		(fp_line
			(start -0.1651 -0.0508)
			(end -0.1651 0.5842)
			(stroke
				(width 0.1)
				(type default)
			)
			(layer "B.Fab")
		)
		(pad "1" smd custom
			(at 0 0 180)
			(size 0.0762 0.0762)
			(layers "B.Cu" "B.Mask" "B.Paste")
			(net "VSENSE_PVCCIO_CPU0_SKT_VSEN")
			(options
				(clearance outline)
				(anchor circle)
			)
			(primitives
				(gr_poly
					(pts
						(arc
							(start -0.1524 0.10795)
							(mid -0.098518 0.130268)
							(end -0.0762 0.18415)
						)
						(xy -0.0762 0.22225) (xy 0.0762 0.22225)
						(arc
							(start 0.0762 0.18415)
							(mid 0.098518 0.130268)
							(end 0.1524 0.10795)
						)
						(xy 0.1524 -0.22225) (xy -0.1524 -0.22225)
					)
					(width 0)
					(fill yes)
				)
			)
		)
		(pad "2" smd custom
			(at 0 0.5334)
			(size 0.0762 0.0762)
			(layers "B.Cu" "B.Mask" "B.Paste")
			(net "VSENSE_PVCCIO_CPU0_AVSP")
			(options
				(clearance outline)
				(anchor circle)
			)
			(primitives
				(gr_poly
					(pts
						(arc
							(start -0.1524 0.10795)
							(mid -0.098518 0.130268)
							(end -0.0762 0.18415)
						)
						(xy -0.0762 0.22225) (xy 0.0762 0.22225)
						(arc
							(start 0.0762 0.18415)
							(mid 0.098518 0.130268)
							(end 0.1524 0.10795)
						)
						(xy 0.1524 -0.22225) (xy -0.1524 -0.22225)
					)
					(width 0)
					(fill yes)
				)
			)
		)
	)
)
